# BASEBOARD_FAB2 (Tioga Pass) — schematic netlist excerpt (pin names and nets, part order shuffled) for the footprints in the layout excerpt that follows; sources: Cadence DE-HDL packaged netlist, KiCad conversion of Wiwynn_Tioga_Pass_MB.brd

C3P24  CAP  0.22UF 16V 10% X7R  pkg 0402  page 107 : A = P3E_CPU0_PE1_SS_TXN<3> ; B = P3E_CPU0_PE1_SS_C_TXN<3>
C6P14  CAPP  470UF 2.5V 20% ALUM  pkg 3018  page 203 : A = PVCCIN_CPU0 ; B = GND
R8D15  RES  1.37K 1% CHIP  pkg 0402  page 138 : A = P3V3_STBY ; B = SMB_VR_STBY_LVC3_SCL

(kicad_pcb
	(version 20260206)
	(generator "pcbnew")
	(generator_version "10.0")
	(general
		(thickness 1.6)
		(legacy_teardrops no)
	)
	(paper "A4")
	(title_block
		(title "Wiwynn_Tioga_Pass_MB.brd")
		(comment 1 "Tioga Pass / footprints 3968-3970 of 4770")
	)
	(layers
		(0 "F.Cu" signal "TOP")
		(4 "In1.Cu" signal "L2GND")
		(6 "In2.Cu" signal "L3")
		(8 "In3.Cu" signal "L4GND")
		(10 "In4.Cu" signal "L5")
		(12 "In5.Cu" signal "L6GND")
		(14 "In6.Cu" signal "L7VCC")
		(16 "In7.Cu" signal "L8VCC")
		(18 "In8.Cu" signal "L9GND")
		(20 "In9.Cu" signal "L10")
		(22 "In10.Cu" signal "L11GND")
		(24 "In11.Cu" signal "L12")
		(26 "In12.Cu" signal "L13GND")
		(2 "B.Cu" signal "BOTTOM")
		(9 "F.Adhes" user "F.Adhesive")
		(11 "B.Adhes" user "B.Adhesive")
		(13 "F.Paste" user "Package Geometry/Pastemask Top")
		(15 "B.Paste" user "Package Geometry/Pastemask Bottom")
		(5 "F.SilkS" user "Ref Des/Silkscreen Top")
		(7 "B.SilkS" user "Ref Des/Silkscreen Bottom")
		(1 "F.Mask" user "Board Geometry/Soldermask Top")
		(3 "B.Mask" user "Board Geometry/Soldermask Bottom")
		(17 "Dwgs.User" user "User.Drawings")
		(19 "Cmts.User" user "User.Comments")
		(21 "Eco1.User" user "User.Eco1")
		(23 "Eco2.User" user "User.Eco2")
		(25 "Edge.Cuts" user "Board Geometry/Outline")
		(27 "Margin" user)
		(31 "F.CrtYd" user "Package Geometry/Place Bound Top")
		(29 "B.CrtYd" user "Package Geometry/Place Bound Bottom")
		(35 "F.Fab" user "Ref Des/Assembly Top")
		(33 "B.Fab" user "Ref Des/Assembly Bottom")
	)
	(footprint ""
		(layer "B.Cu")
		(at 210.847432 -78.867 -90)
		(property "Reference" "C6P14"
			(at -2.00533 -3.909568 0)
			(unlocked yes)
			(layer "B.SilkS")
			(effects
				(font
					(size 0.7874 0.5842)
					(thickness 0.1524)
				)
				(justify mirror)
			)
		)
		(property "Value" ""
			(at 0 0 90)
			(layer "B.Fab")
			(effects
				(font
					(size 1.27 1.27)
				)
				(justify mirror)
			)
		)
		(duplicate_pad_numbers_are_jumpers no)
		(fp_line
			(start -2.286 7.366)
			(end -1.600708 7.366)
			(stroke
				(width 0.1524)
				(type default)
			)
			(layer "B.SilkS")
		)
		(fp_line
			(start -2.286 7.366)
			(end -2.286 1.63195)
			(stroke
				(width 0.1524)
				(type default)
			)
			(layer "B.SilkS")
		)
		(fp_line
			(start 2.286 7.366)
			(end 1.60147 7.366)
			(stroke
				(width 0.1524)
				(type default)
			)
			(layer "B.SilkS")
		)
		(fp_line
			(start 2.286 7.366)
			(end 2.286 1.632712)
			(stroke
				(width 0.1524)
				(type default)
			)
			(layer "B.SilkS")
		)
		(fp_line
			(start -2.504948 1.633728)
			(end -1.6002 1.633728)
			(stroke
				(width 0.1524)
				(type default)
			)
			(layer "B.SilkS")
		)
		(fp_line
			(start 2.563114 1.633728)
			(end 1.6002 1.633728)
			(stroke
				(width 0.1524)
				(type default)
			)
			(layer "B.SilkS")
		)
		(fp_line
			(start -2.504948 -1.616456)
			(end -2.504948 1.633728)
			(stroke
				(width 0.1524)
				(type default)
			)
			(layer "B.SilkS")
		)
		(fp_line
			(start -1.6002 -1.616456)
			(end -2.504948 -1.616456)
			(stroke
				(width 0.1524)
				(type default)
			)
			(layer "B.SilkS")
		)
		(fp_line
			(start 1.6002 -1.616456)
			(end 2.563114 -1.616456)
			(stroke
				(width 0.1524)
				(type default)
			)
			(layer "B.SilkS")
		)
		(fp_line
			(start 2.563114 -1.616456)
			(end 2.563114 1.633728)
			(stroke
				(width 0.1524)
				(type default)
			)
			(layer "B.SilkS")
		)
		(fp_rect
			(start 2.286 7.366)
			(end -2.286 -0.254)
			(stroke
				(width 0)
				(type default)
			)
			(fill no)
			(layer "B.CrtYd")
		)
		(fp_line
			(start -2.286 7.366)
			(end 2.286 7.366)
			(stroke
				(width 0.1)
				(type default)
			)
			(layer "B.Fab")
		)
		(fp_line
			(start 2.286 7.366)
			(end 2.286 -0.254)
			(stroke
				(width 0.1)
				(type default)
			)
			(layer "B.Fab")
		)
		(fp_line
			(start -2.286 -0.254)
			(end -2.286 7.366)
			(stroke
				(width 0.1)
				(type default)
			)
			(layer "B.Fab")
		)
		(fp_line
			(start 2.286 -0.254)
			(end -2.286 -0.254)
			(stroke
				(width 0.1)
				(type default)
			)
			(layer "B.Fab")
		)
		(pad "1" smd rect
			(at 0 0 90)
			(size 2.54 3.048)
			(layers "B.Cu" "B.Mask" "B.Paste")
			(net "PVCCIN_CPU0")
		)
		(pad "2" smd rect
			(at 0 7.112 90)
			(size 2.54 3.048)
			(layers "B.Cu" "B.Mask" "B.Paste")
			(net "GND")
		)
	)
	(footprint ""
		(layer "B.Cu")
		(at 348.57436 -77.788516)
		(property "Reference" "C3P24"
			(at 0 0 0)
			(layer "B.SilkS")
			(hide yes)
			(effects
				(font
					(size 1.27 1.27)
				)
				(justify mirror)
			)
		)
		(property "Value" ""
			(at 0 0 0)
			(layer "B.Fab")
			(effects
				(font
					(size 1.27 1.27)
				)
				(justify mirror)
			)
		)
		(duplicate_pad_numbers_are_jumpers no)
		(fp_poly
			(pts
				(xy -0.3048 -0.1016) (xy -0.3048 0.9906) (xy 0.3048 0.9906) (xy 0.3048 -0.1016)
			)
			(stroke
				(width 0)
				(type default)
			)
			(fill no)
			(layer "B.CrtYd")
		)
		(fp_line
			(start -0.3048 -0.1016)
			(end 0.3048 -0.1016)
			(stroke
				(width 0.1)
				(type default)
			)
			(layer "B.Fab")
		)
		(fp_line
			(start -0.3048 0.9906)
			(end -0.3048 -0.1016)
			(stroke
				(width 0.1)
				(type default)
			)
			(layer "B.Fab")
		)
		(fp_line
			(start 0.3048 -0.1016)
			(end 0.3048 0.9906)
			(stroke
				(width 0.1)
				(type default)
			)
			(layer "B.Fab")
		)
		(fp_line
			(start 0.3048 0.9906)
			(end -0.3048 0.9906)
			(stroke
				(width 0.1)
				(type default)
			)
			(layer "B.Fab")
		)
		(pad "1" smd rect
			(at 0 0 180)
			(size 0.508 0.508)
			(layers "B.Cu" "B.Mask" "B.Paste")
			(net "P3E_CPU0_PE1_SS_TXN<3>")
		)
		(pad "2" smd rect
			(at 0 0.889 180)
			(size 0.508 0.508)
			(layers "B.Cu" "B.Mask" "B.Paste")
			(net "P3E_CPU0_PE1_SS_C_TXN<3>")
		)
		(zone
			(layer "B.Cu")
			(hatch none 0.5)
			(connect_pads
				(clearance 0)
			)
			(min_thickness 0.25)
			(keepout
				(tracks allowed)
				(vias not_allowed)
				(pads allowed)
				(copperpour not_allowed)
				(footprints allowed)
			)
			(placement
				(enabled no)
				(sheetname "")
			)
			(fill
				(thermal_gap 0.5)
				(thermal_bridge_width 0.5)
				(island_removal_mode 0)
			)
			(polygon
				(pts
					(xy 348.82836 -77.534516) (xy 348.32036 -77.534516) (xy 348.32036 -77.153516) (xy 348.82836 -77.153516)
				)
			)
		)
		(zone
			(layer "B.Cu")
			(hatch none 0.5)
			(connect_pads
				(clearance 0)
			)
			(min_thickness 0.25)
			(keepout
				(tracks not_allowed)
				(vias allowed)
				(pads allowed)
				(copperpour not_allowed)
				(footprints allowed)
			)
			(placement
				(enabled no)
				(sheetname "")
			)
			(fill
				(thermal_gap 0.5)
				(thermal_bridge_width 0.5)
				(island_removal_mode 0)
			)
			(polygon
				(pts
					(xy 348.82836 -77.153516) (xy 348.32036 -77.153516) (xy 348.32036 -77.534516) (xy 348.82836 -77.534516)
				)
			)
		)
	)
	(footprint ""
		(layer "B.Cu")
		(at 397.002 -85.0265 180)
		(property "Reference" "R8D15"
			(at 0.8382 -0.67818 180)
			(unlocked yes)
			(layer "B.SilkS")
			(effects
				(font
					(size 0.4064 0.254)
					(thickness 0.1524)
				)
				(justify left mirror)
			)
		)
		(property "Value" ""
			(at 0 0 0)
			(layer "B.Fab")
			(effects
				(font
					(size 1.27 1.27)
				)
				(justify mirror)
			)
		)
		(duplicate_pad_numbers_are_jumpers no)
		(fp_poly
			(pts
				(xy 0.2794 -0.1016) (xy -0.2794 -0.1016) (xy -0.2794 0.9906) (xy 0.2794 0.9906)
			)
			(stroke
				(width 0)
				(type default)
			)
			(fill no)
			(layer "B.CrtYd")
		)
		(fp_line
			(start 0.2794 0.9906)
			(end -0.2794 0.9906)
			(stroke
				(width 0.1)
				(type default)
			)
			(layer "B.Fab")
		)
		(fp_line
			(start 0.2794 -0.1016)
			(end 0.2794 0.9906)
			(stroke
				(width 0.1)
				(type default)
			)
			(layer "B.Fab")
		)
		(fp_line
			(start -0.2794 0.9906)
			(end -0.2794 -0.1016)
			(stroke
				(width 0.1)
				(type default)
			)
			(layer "B.Fab")
		)
		(fp_line
			(start -0.2794 -0.1016)
			(end 0.2794 -0.1016)
			(stroke
				(width 0.1)
				(type default)
			)
			(layer "B.Fab")
		)
		(pad "1" smd rect
			(at 0 0)
			(size 0.508 0.508)
			(layers "B.Cu" "B.Mask" "B.Paste")
			(net "P3V3_STBY")
		)
		(pad "2" smd rect
			(at 0 0.889)
			(size 0.508 0.508)
			(layers "B.Cu" "B.Mask" "B.Paste")
			(net "SMB_VR_STBY_LVC3_SCL")
		)
		(zone
			(layer "B.Cu")
			(hatch none 0.5)
			(connect_pads
				(clearance 0)
			)
			(min_thickness 0.25)
			(keepout
				(tracks not_allowed)
				(vias allowed)
				(pads allowed)
				(copperpour not_allowed)
				(footprints allowed)
			)
			(placement
				(enabled no)
				(sheetname "")
			)
			(fill
				(thermal_gap 0.5)
				(thermal_bridge_width 0.5)
				(island_removal_mode 0)
			)
			(polygon
				(pts
					(xy 396.748 -85.6615) (xy 397.256 -85.6615) (xy 397.256 -85.2805) (xy 396.748 -85.2805)
				)
			)
		)
		(zone
			(layer "B.Cu")
			(hatch none 0.5)
			(connect_pads
				(clearance 0)
			)
			(min_thickness 0.25)
			(keepout
				(tracks allowed)
				(vias not_allowed)
				(pads allowed)
				(copperpour not_allowed)
				(footprints allowed)
			)
			(placement
				(enabled no)
				(sheetname "")
			)
			(fill
				(thermal_gap 0.5)
				(thermal_bridge_width 0.5)
				(island_removal_mode 0)
			)
			(polygon
				(pts
					(xy 396.748 -85.2805) (xy 397.256 -85.2805) (xy 397.256 -85.6615) (xy 396.748 -85.6615)
				)
			)
		)
	)
)
